# T6G (Grand Teton) — schematic netlist excerpt (pin names and nets, part order shuffled) for the footprints in the layout excerpt that follows; sources: Cadence DE-HDL packaged netlist, KiCad conversion of 04192023_DAF0TMB3IC0_F0TG_MB_C_brd_V02_OCP.brd

R60  Q_RES  10K 1% EMPTY  pkg 0402LF  page 238 : A = P3V3_AUX ; B = CPU_FRU_ADDR1
PC608_3  Q_CAP  1UF 25V 10% X6S  pkg C0402  page 199 : A = SW_P12V_AUX_PVDDCR_SOC_P0_FLT ; B = GND

(kicad_pcb
	(version 20260206)
	(generator "pcbnew")
	(generator_version "10.0")
	(general
		(thickness 1.6)
		(legacy_teardrops no)
	)
	(paper "A4")
	(title_block
		(title "04192023_DAF0TMB3IC0_F0TG_MB_C_brd_V02_OCP.brd")
		(comment 1 "Grand Teton / footprints 1038-1039 of 8354")
	)
	(layers
		(0 "F.Cu" signal "TOP")
		(4 "In1.Cu" signal "GND")
		(6 "In2.Cu" signal "IN1")
		(8 "In3.Cu" signal "GND1")
		(10 "In4.Cu" signal "IN2")
		(12 "In5.Cu" signal "GND2")
		(14 "In6.Cu" signal "IN3")
		(16 "In7.Cu" signal "GND3")
		(18 "In8.Cu" signal "VCC")
		(20 "In9.Cu" signal "VCC1")
		(22 "In10.Cu" signal "GND4")
		(24 "In11.Cu" signal "IN4")
		(26 "In12.Cu" signal "GND5")
		(28 "In13.Cu" signal "IN5")
		(30 "In14.Cu" signal "GND6")
		(32 "In15.Cu" signal "IN6")
		(34 "In16.Cu" signal "GND7")
		(2 "B.Cu" signal "BOTTOM")
		(9 "F.Adhes" user "F.Adhesive")
		(11 "B.Adhes" user "B.Adhesive")
		(13 "F.Paste" user "Package Geometry/Pastemask Top")
		(15 "B.Paste" user "Package Geometry/Pastemask Bottom")
		(5 "F.SilkS" user "Ref Des/Silkscreen Top")
		(7 "B.SilkS" user "Ref Des/Silkscreen Bottom")
		(1 "F.Mask" user "Board Geometry/Soldermask Top")
		(3 "B.Mask" user "Board Geometry/Soldermask Bottom")
		(17 "Dwgs.User" user "User.Drawings")
		(19 "Cmts.User" user "User.Comments")
		(21 "Eco1.User" user "User.Eco1")
		(23 "Eco2.User" user "User.Eco2")
		(25 "Edge.Cuts" user "Board Geometry/Outline")
		(27 "Margin" user)
		(31 "F.CrtYd" user "Package Geometry/Place Bound Top")
		(29 "B.CrtYd" user "Package Geometry/Place Bound Bottom")
		(35 "F.Fab" user "Ref Des/Assembly Top")
		(33 "B.Fab" user "Ref Des/Assembly Bottom")
	)
	(footprint ""
		(layer "F.Cu")
		(at 302.241458 -112.827308)
		(property "Reference" "R60"
			(at 0 0 0)
			(layer "F.SilkS")
			(hide yes)
			(effects
				(font
					(size 1.27 1.27)
				)
			)
		)
		(property "Value" ""
			(at 0 0 0)
			(layer "F.Fab")
			(effects
				(font
					(size 1.27 1.27)
				)
			)
		)
		(duplicate_pad_numbers_are_jumpers no)
		(fp_line
			(start -0.7874 -0.4064)
			(end 0.7874 -0.4064)
			(stroke
				(width 0.1524)
				(type default)
			)
			(layer "F.SilkS")
		)
		(fp_line
			(start -0.7874 0.4064)
			(end -0.7874 -0.4064)
			(stroke
				(width 0.1524)
				(type default)
			)
			(layer "F.SilkS")
		)
		(fp_line
			(start 0.7874 -0.4064)
			(end 0.7874 0.4064)
			(stroke
				(width 0.1524)
				(type default)
			)
			(layer "F.SilkS")
		)
		(fp_line
			(start 0.7874 0.4064)
			(end -0.7874 0.4064)
			(stroke
				(width 0.1524)
				(type default)
			)
			(layer "F.SilkS")
		)
		(fp_line
			(start -0.67945 -0.305054)
			(end -0.12065 -0.305054)
			(stroke
				(width 0.1)
				(type default)
			)
			(layer "F.Fab")
		)
		(fp_line
			(start -0.67945 0.3048)
			(end -0.67945 -0.305054)
			(stroke
				(width 0.1)
				(type default)
			)
			(layer "F.Fab")
		)
		(fp_line
			(start -0.12065 -0.305054)
			(end -0.12065 -0.2794)
			(stroke
				(width 0.1)
				(type default)
			)
			(layer "F.Fab")
		)
		(fp_line
			(start -0.12065 -0.2794)
			(end 0.12065 -0.2794)
			(stroke
				(width 0.1)
				(type default)
			)
			(layer "F.Fab")
		)
		(fp_line
			(start -0.12065 0.2794)
			(end -0.12065 0.3048)
			(stroke
				(width 0.1)
				(type default)
			)
			(layer "F.Fab")
		)
		(fp_line
			(start -0.12065 0.3048)
			(end -0.67945 0.3048)
			(stroke
				(width 0.1)
				(type default)
			)
			(layer "F.Fab")
		)
		(fp_line
			(start 0.120396 0.2794)
			(end -0.12065 0.2794)
			(stroke
				(width 0.1)
				(type default)
			)
			(layer "F.Fab")
		)
		(fp_line
			(start 0.120396 0.3048)
			(end 0.120396 0.2794)
			(stroke
				(width 0.1)
				(type default)
			)
			(layer "F.Fab")
		)
		(fp_line
			(start 0.12065 -0.3048)
			(end 0.67945 -0.3048)
			(stroke
				(width 0.1)
				(type default)
			)
			(layer "F.Fab")
		)
		(fp_line
			(start 0.12065 -0.2794)
			(end 0.12065 -0.3048)
			(stroke
				(width 0.1)
				(type default)
			)
			(layer "F.Fab")
		)
		(fp_line
			(start 0.67945 -0.3048)
			(end 0.67945 0.3048)
			(stroke
				(width 0.1)
				(type default)
			)
			(layer "F.Fab")
		)
		(fp_line
			(start 0.67945 0.3048)
			(end 0.120396 0.3048)
			(stroke
				(width 0.1)
				(type default)
			)
			(layer "F.Fab")
		)
		(pad "1" smd circle
			(at -0.40005 0)
			(size 0 0)
			(layers "F.Cu" "F.Mask" "F.Paste")
			(net "P3V3_AUX")
		)
		(pad "2" smd circle
			(at 0.40005 0)
			(size 0 0)
			(layers "F.Cu" "F.Mask" "F.Paste")
			(net "CPU_FRU_ADDR1")
		)
	)
	(footprint ""
		(layer "F.Cu")
		(at 410.869638 -163.684966 90)
		(property "Reference" "PC608_3"
			(at 0 0 90)
			(layer "F.SilkS")
			(hide yes)
			(effects
				(font
					(size 1.27 1.27)
				)
			)
		)
		(property "Value" ""
			(at 0 0 90)
			(layer "F.Fab")
			(effects
				(font
					(size 1.27 1.27)
				)
			)
		)
		(duplicate_pad_numbers_are_jumpers no)
		(fp_line
			(start 0.7874 -0.4064)
			(end 0.7874 0.4064)
			(stroke
				(width 0.1524)
				(type default)
			)
			(layer "F.SilkS")
		)
		(fp_line
			(start -0.7874 -0.4064)
			(end 0.7874 -0.4064)
			(stroke
				(width 0.1524)
				(type default)
			)
			(layer "F.SilkS")
		)
		(fp_line
			(start 0.7874 0.4064)
			(end -0.7874 0.4064)
			(stroke
				(width 0.1524)
				(type default)
			)
			(layer "F.SilkS")
		)
		(fp_line
			(start -0.7874 0.4064)
			(end -0.7874 -0.4064)
			(stroke
				(width 0.1524)
				(type default)
			)
			(layer "F.SilkS")
		)
		(fp_line
			(start -0.12065 -0.305054)
			(end -0.12065 -0.2794)
			(stroke
				(width 0.1)
				(type default)
			)
			(layer "F.Fab")
		)
		(fp_line
			(start -0.67945 -0.305054)
			(end -0.12065 -0.305054)
			(stroke
				(width 0.1)
				(type default)
			)
			(layer "F.Fab")
		)
		(fp_line
			(start 0.67945 -0.3048)
			(end 0.67945 0.3048)
			(stroke
				(width 0.1)
				(type default)
			)
			(layer "F.Fab")
		)
		(fp_line
			(start 0.12065 -0.3048)
			(end 0.67945 -0.3048)
			(stroke
				(width 0.1)
				(type default)
			)
			(layer "F.Fab")
		)
		(fp_line
			(start 0.12065 -0.2794)
			(end 0.12065 -0.3048)
			(stroke
				(width 0.1)
				(type default)
			)
			(layer "F.Fab")
		)
		(fp_line
			(start -0.12065 -0.2794)
			(end 0.12065 -0.2794)
			(stroke
				(width 0.1)
				(type default)
			)
			(layer "F.Fab")
		)
		(fp_line
			(start 0.120396 0.2794)
			(end -0.12065 0.2794)
			(stroke
				(width 0.1)
				(type default)
			)
			(layer "F.Fab")
		)
		(fp_line
			(start -0.12065 0.2794)
			(end -0.12065 0.3048)
			(stroke
				(width 0.1)
				(type default)
			)
			(layer "F.Fab")
		)
		(fp_line
			(start 0.67945 0.3048)
			(end 0.120396 0.3048)
			(stroke
				(width 0.1)
				(type default)
			)
			(layer "F.Fab")
		)
		(fp_line
			(start 0.120396 0.3048)
			(end 0.120396 0.2794)
			(stroke
				(width 0.1)
				(type default)
			)
			(layer "F.Fab")
		)
		(fp_line
			(start -0.12065 0.3048)
			(end -0.67945 0.3048)
			(stroke
				(width 0.1)
				(type default)
			)
			(layer "F.Fab")
		)
		(fp_line
			(start -0.67945 0.3048)
			(end -0.67945 -0.305054)
			(stroke
				(width 0.1)
				(type default)
			)
			(layer "F.Fab")
		)
		(pad "1" smd circle
			(at -0.40005 0 90)
			(size 0 0)
			(layers "F.Cu" "F.Mask" "F.Paste")
			(net "SW_P12V_AUX_PVDDCR_SOC_P0_FLT")
		)
		(pad "2" smd circle
			(at 0.40005 0 90)
			(size 0 0)
			(layers "F.Cu" "F.Mask" "F.Paste")
			(net "GND")
		)
	)
)
